(kicad_pcb
	(version 20260206)
	(generator "pcbnew")
	(generator_version "10.0")
	(general
		(thickness 1.6)
		(legacy_teardrops no)
	)
	(paper "A4")
	(title_block
		(title "panther-plus-userver — 13130-1b_20150205.brd")
		(comment 1 "Honey Badger (Wiwynn) / footprints 74-79 of 1509")
	)
	(layers
		(0 "F.Cu" signal "TOP")
		(4 "In1.Cu" signal "L2")
		(6 "In2.Cu" signal "L3")
		(8 "In3.Cu" signal "L4")
		(10 "In4.Cu" signal "L5")
		(12 "In5.Cu" signal "L6")
		(14 "In6.Cu" signal "L7")
		(16 "In7.Cu" signal "L8")
		(18 "In8.Cu" signal "L9")
		(20 "In9.Cu" signal "L10")
		(22 "In10.Cu" signal "L11")
		(2 "B.Cu" signal "BOTTOM")
		(9 "F.Adhes" user "F.Adhesive")
		(11 "B.Adhes" user "B.Adhesive")
		(13 "F.Paste" user "Package Geometry/Pastemask Top")
		(15 "B.Paste" user "Package Geometry/Pastemask Bottom")
		(5 "F.SilkS" user "Ref Des/Silkscreen Top")
		(7 "B.SilkS" user "Ref Des/Silkscreen Bottom")
		(1 "F.Mask" user "Board Geometry/Soldermask Top")
		(3 "B.Mask" user "Board Geometry/Soldermask Bottom")
		(17 "Dwgs.User" user "User.Drawings")
		(19 "Cmts.User" user "User.Comments")
		(21 "Eco1.User" user "User.Eco1")
		(23 "Eco2.User" user "User.Eco2")
		(25 "Edge.Cuts" user "Board Geometry/Outline")
		(27 "Margin" user)
		(31 "F.CrtYd" user "Package Geometry/Place Bound Top")
		(29 "B.CrtYd" user "Package Geometry/Place Bound Bottom")
		(35 "F.Fab" user "Ref Des/Assembly Top")
		(33 "B.Fab" user "Ref Des/Assembly Bottom")
	)
	(footprint ""
		(layer "F.Cu")
		(at 182.118 -51.181 180)
		(property "Reference" "C93"
			(at 0 0 180)
			(layer "F.SilkS")
			(hide yes)
			(effects
				(font
					(size 1.27 1.27)
				)
			)
		)
		(property "Value" "SCD1U16V2KX-3GP"
			(at 1.1811 -2.7051 180)
			(unlocked yes)
			(layer "F.Fab")
			(hide yes)
			(effects
				(font
					(size 1.016 1.016)
					(thickness 0.1524)
				)
			)
		)
		(property "Device Type" "C402H22"
			(at 1.1811 -4.2291 180)
			(unlocked yes)
			(layer "F.Fab")
			(hide yes)
			(effects
				(font
					(size 1.016 1.016)
					(thickness 0.1524)
				)
			)
		)
		(duplicate_pad_numbers_are_jumpers no)
		(fp_rect
			(start -0.381 0.7366)
			(end 0.381 -0.7366)
			(stroke
				(width 0)
				(type default)
			)
			(fill no)
			(layer "F.CrtYd")
		)
		(fp_rect
			(start -0.381 0.7366)
			(end 0.381 -0.7366)
			(stroke
				(width 0)
				(type default)
			)
			(fill no)
			(layer "F.Fab")
		)
		(pad "1" smd custom
			(at 0 -0.4572 180)
			(size 0.1143 0.1143)
			(layers "F.Cu" "F.Mask" "F.Paste")
			(net "P3V3_STBY")
			(options
				(clearance outline)
				(anchor circle)
			)
			(primitives
				(gr_poly
					(pts
						(arc
							(start -0.254 -0.1778)
							(mid -0.239121 -0.213721)
							(end -0.2032 -0.2286)
						)
						(arc
							(start 0.2032 -0.2286)
							(mid 0.239121 -0.213721)
							(end 0.254 -0.1778)
						)
						(arc
							(start 0.254 0.1778)
							(mid 0.239121 0.213721)
							(end 0.2032 0.2286)
						)
						(arc
							(start -0.2032 0.2286)
							(mid -0.239121 0.213721)
							(end -0.254 0.1778)
						)
					)
					(width 0)
					(fill yes)
				)
			)
		)
		(pad "2" smd custom
			(at 0 0.4572 180)
			(size 0.1143 0.1143)
			(layers "F.Cu" "F.Mask" "F.Paste")
			(net "GND")
			(options
				(clearance outline)
				(anchor circle)
			)
			(primitives
				(gr_poly
					(pts
						(arc
							(start -0.254 -0.1778)
							(mid -0.239121 -0.213721)
							(end -0.2032 -0.2286)
						)
						(arc
							(start 0.2032 -0.2286)
							(mid 0.239121 -0.213721)
							(end 0.254 -0.1778)
						)
						(arc
							(start 0.254 0.1778)
							(mid 0.239121 0.213721)
							(end 0.2032 0.2286)
						)
						(arc
							(start -0.2032 0.2286)
							(mid -0.239121 0.213721)
							(end -0.254 0.1778)
						)
					)
					(width 0)
					(fill yes)
				)
			)
		)
	)
	(footprint ""
		(layer "F.Cu")
		(at 135.001 -59.817 180)
		(property "Reference" "PR59"
			(at 0 0 180)
			(layer "F.SilkS")
			(hide yes)
			(effects
				(font
					(size 1.27 1.27)
				)
			)
		)
		(property "Value" "20KR2F-L-GP"
			(at 0.064008 -3.993896 180)
			(unlocked yes)
			(layer "F.Fab")
			(hide yes)
			(effects
				(font
					(size 1.016 1.016)
					(thickness 0.1524)
				)
			)
		)
		(property "Device Type" "R402H16"
			(at 0.064008 -5.517896 180)
			(unlocked yes)
			(layer "F.Fab")
			(hide yes)
			(effects
				(font
					(size 1.016 1.016)
					(thickness 0.1524)
				)
			)
		)
		(duplicate_pad_numbers_are_jumpers no)
		(fp_rect
			(start -0.381 0.8382)
			(end 0.381 -0.8382)
			(stroke
				(width 0)
				(type default)
			)
			(fill no)
			(layer "F.CrtYd")
		)
		(fp_rect
			(start -0.381 0.8382)
			(end 0.381 -0.8382)
			(stroke
				(width 0)
				(type default)
			)
			(fill no)
			(layer "F.Fab")
		)
		(pad "1" smd custom
			(at 0 -0.4318 180)
			(size 0.127 0.127)
			(layers "F.Cu" "F.Mask" "F.Paste")
			(net "PV_VDDR")
			(options
				(clearance outline)
				(anchor circle)
			)
			(primitives
				(gr_poly
					(pts
						(arc
							(start -0.2032 -0.2794)
							(mid -0.239121 -0.264521)
							(end -0.254 -0.2286)
						)
						(arc
							(start -0.254 0.2286)
							(mid -0.239121 0.264521)
							(end -0.2032 0.2794)
						)
						(arc
							(start 0.2032 0.2794)
							(mid 0.239121 0.264521)
							(end 0.254 0.2286)
						)
						(arc
							(start 0.254 -0.2286)
							(mid 0.239121 -0.264521)
							(end 0.2032 -0.2794)
						)
					)
					(width 0)
					(fill yes)
				)
			)
		)
		(pad "2" smd custom
			(at 0 0.4318 180)
			(size 0.127 0.127)
			(layers "F.Cu" "F.Mask" "F.Paste")
			(net "PV_VTT_DDR_REFIN")
			(options
				(clearance outline)
				(anchor circle)
			)
			(primitives
				(gr_poly
					(pts
						(arc
							(start -0.2032 -0.2794)
							(mid -0.239121 -0.264521)
							(end -0.254 -0.2286)
						)
						(arc
							(start -0.254 0.2286)
							(mid -0.239121 0.264521)
							(end -0.2032 0.2794)
						)
						(arc
							(start 0.2032 0.2794)
							(mid 0.239121 0.264521)
							(end 0.254 0.2286)
						)
						(arc
							(start 0.254 -0.2286)
							(mid 0.239121 -0.264521)
							(end 0.2032 -0.2794)
						)
					)
					(width 0)
					(fill yes)
				)
			)
		)
	)
	(footprint ""
		(layer "F.Cu")
		(at 119.8118 -64.643 -90)
		(property "Reference" "C103"
			(at 0 0 270)
			(layer "F.SilkS")
			(hide yes)
			(effects
				(font
					(size 1.27 1.27)
				)
			)
		)
		(property "Value" "SC10U6D3V3MX-GP"
			(at 0 -2.8194 270)
			(unlocked yes)
			(layer "F.Fab")
			(hide yes)
			(effects
				(font
					(size 1.016 1.016)
					(thickness 0.1524)
				)
			)
		)
		(property "Device Type" "C603H38"
			(at 0 -4.3434 270)
			(unlocked yes)
			(layer "F.Fab")
			(hide yes)
			(effects
				(font
					(size 1.016 1.016)
					(thickness 0.1524)
				)
			)
		)
		(duplicate_pad_numbers_are_jumpers no)
		(fp_line
			(start -0.4064 0)
			(end 0.4064 0)
			(stroke
				(width 0.2286)
				(type default)
			)
			(layer "F.SilkS")
		)
		(fp_rect
			(start -0.635 1.1811)
			(end 0.635 -1.1811)
			(stroke
				(width 0)
				(type default)
			)
			(fill no)
			(layer "F.CrtYd")
		)
		(fp_rect
			(start -0.635 1.1811)
			(end 0.635 -1.1811)
			(stroke
				(width 0)
				(type default)
			)
			(fill no)
			(layer "F.Fab")
		)
		(pad "1" smd custom
			(at 0 -0.6604 270)
			(size 0.19685 0.19685)
			(layers "F.Cu" "F.Mask" "F.Paste")
			(net "PV_VTT_DDR_A")
			(options
				(clearance outline)
				(anchor circle)
			)
			(primitives
				(gr_poly
					(pts
						(arc
							(start 0.508 -0.2921)
							(mid 0.478242 -0.363942)
							(end 0.4064 -0.3937)
						)
						(arc
							(start -0.4064 -0.3937)
							(mid -0.478242 -0.363942)
							(end -0.508 -0.2921)
						)
						(arc
							(start -0.508 0.2921)
							(mid -0.478242 0.363942)
							(end -0.4064 0.3937)
						)
						(arc
							(start 0.4064 0.3937)
							(mid 0.478242 0.363942)
							(end 0.508 0.2921)
						)
					)
					(width 0)
					(fill yes)
				)
			)
		)
		(pad "2" smd custom
			(at 0 0.6604 270)
			(size 0.19685 0.19685)
			(layers "F.Cu" "F.Mask" "F.Paste")
			(net "GND")
			(options
				(clearance outline)
				(anchor circle)
			)
			(primitives
				(gr_poly
					(pts
						(arc
							(start 0.508 -0.2921)
							(mid 0.478242 -0.363942)
							(end 0.4064 -0.3937)
						)
						(arc
							(start -0.4064 -0.3937)
							(mid -0.478242 -0.363942)
							(end -0.508 -0.2921)
						)
						(arc
							(start -0.508 0.2921)
							(mid -0.478242 0.363942)
							(end -0.4064 0.3937)
						)
						(arc
							(start 0.4064 0.3937)
							(mid 0.478242 0.363942)
							(end 0.508 0.2921)
						)
					)
					(width 0)
					(fill yes)
				)
			)
		)
	)
	(footprint ""
		(layer "F.Cu")
		(at 21.1836 -52.0954)
		(property "Reference" "PR75"
			(at 0 0 0)
			(layer "F.SilkS")
			(hide yes)
			(effects
				(font
					(size 1.27 1.27)
				)
			)
		)
		(property "Value" "0R2J-2-GP"
			(at 1.7907 -1.1176 0)
			(unlocked yes)
			(layer "F.Fab")
			(hide yes)
			(effects
				(font
					(size 1.016 1.016)
					(thickness 0.1524)
				)
			)
		)
		(property "Device Type" "R402H16"
			(at 1.7907 -2.6416 0)
			(unlocked yes)
			(layer "F.Fab")
			(hide yes)
			(effects
				(font
					(size 1.016 1.016)
					(thickness 0.1524)
				)
			)
		)
		(duplicate_pad_numbers_are_jumpers no)
		(fp_rect
			(start -0.381 0.8382)
			(end 0.381 -0.8382)
			(stroke
				(width 0)
				(type default)
			)
			(fill no)
			(layer "F.CrtYd")
		)
		(fp_rect
			(start -0.381 0.8382)
			(end 0.381 -0.8382)
			(stroke
				(width 0)
				(type default)
			)
			(fill no)
			(layer "F.Fab")
		)
		(pad "1" smd custom
			(at 0 -0.4318)
			(size 0.127 0.127)
			(layers "F.Cu" "F.Mask" "F.Paste")
			(net "VR_PVCCP_ISEN1_R")
			(options
				(clearance outline)
				(anchor circle)
			)
			(primitives
				(gr_poly
					(pts
						(arc
							(start -0.2032 -0.2794)
							(mid -0.239121 -0.264521)
							(end -0.254 -0.2286)
						)
						(arc
							(start -0.254 0.2286)
							(mid -0.239121 0.264521)
							(end -0.2032 0.2794)
						)
						(arc
							(start 0.2032 0.2794)
							(mid 0.239121 0.264521)
							(end 0.254 0.2286)
						)
						(arc
							(start 0.254 -0.2286)
							(mid 0.239121 -0.264521)
							(end 0.2032 -0.2794)
						)
					)
					(width 0)
					(fill yes)
				)
			)
		)
		(pad "2" smd custom
			(at 0 0.4318)
			(size 0.127 0.127)
			(layers "F.Cu" "F.Mask" "F.Paste")
			(net "VR_PVCCP_ISEN1")
			(options
				(clearance outline)
				(anchor circle)
			)
			(primitives
				(gr_poly
					(pts
						(arc
							(start -0.2032 -0.2794)
							(mid -0.239121 -0.264521)
							(end -0.254 -0.2286)
						)
						(arc
							(start -0.254 0.2286)
							(mid -0.239121 0.264521)
							(end -0.2032 0.2794)
						)
						(arc
							(start 0.2032 0.2794)
							(mid 0.239121 0.264521)
							(end 0.254 0.2286)
						)
						(arc
							(start 0.254 -0.2286)
							(mid 0.239121 -0.264521)
							(end 0.2032 -0.2794)
						)
					)
					(width 0)
					(fill yes)
				)
			)
		)
	)
	(footprint ""
		(layer "F.Cu")
		(at 18.3896 -50.9524)
		(property "Reference" "PR88"
			(at 0 0 0)
			(layer "F.SilkS")
			(hide yes)
			(effects
				(font
					(size 1.27 1.27)
				)
			)
		)
		(property "Value" "100R3F-1-GP"
			(at -0.0254 -2.0193 0)
			(unlocked yes)
			(layer "F.Fab")
			(hide yes)
			(effects
				(font
					(size 1.016 1.016)
					(thickness 0.1524)
				)
			)
		)
		(property "Device Type" "R603H22"
			(at -0.0254 -3.5433 0)
			(unlocked yes)
			(layer "F.Fab")
			(hide yes)
			(effects
				(font
					(size 1.016 1.016)
					(thickness 0.1524)
				)
			)
		)
		(duplicate_pad_numbers_are_jumpers no)
		(fp_line
			(start -0.2032 0)
			(end -0.4191 0)
			(stroke
				(width 0.2032)
				(type default)
			)
			(layer "F.SilkS")
		)
		(fp_line
			(start 0.4318 0)
			(end 0.2032 0)
			(stroke
				(width 0.2032)
				(type default)
			)
			(layer "F.SilkS")
		)
		(fp_rect
			(start -0.635 1.1811)
			(end 0.635 -1.1811)
			(stroke
				(width 0)
				(type default)
			)
			(fill no)
			(layer "F.CrtYd")
		)
		(fp_rect
			(start -0.635 1.1811)
			(end 0.635 -1.1811)
			(stroke
				(width 0)
				(type default)
			)
			(fill no)
			(layer "F.Fab")
		)
		(pad "1" smd custom
			(at 0 -0.6604)
			(size 0.19685 0.19685)
			(layers "F.Cu" "F.Mask" "F.Paste")
			(net "VR_PVCCP_FB")
			(options
				(clearance outline)
				(anchor circle)
			)
			(primitives
				(gr_poly
					(pts
						(arc
							(start 0.508 -0.2921)
							(mid 0.478242 -0.363942)
							(end 0.4064 -0.3937)
						)
						(arc
							(start -0.4064 -0.3937)
							(mid -0.478242 -0.363942)
							(end -0.508 -0.2921)
						)
						(arc
							(start -0.508 0.2921)
							(mid -0.478242 0.363942)
							(end -0.4064 0.3937)
						)
						(arc
							(start 0.4064 0.3937)
							(mid 0.478242 0.363942)
							(end 0.508 0.2921)
						)
					)
					(width 0)
					(fill yes)
				)
			)
		)
		(pad "2" smd custom
			(at 0 0.6604)
			(size 0.19685 0.19685)
			(layers "F.Cu" "F.Mask" "F.Paste")
			(net "VR_PVCCP_VSEN_R")
			(options
				(clearance outline)
				(anchor circle)
			)
			(primitives
				(gr_poly
					(pts
						(arc
							(start 0.508 -0.2921)
							(mid 0.478242 -0.363942)
							(end 0.4064 -0.3937)
						)
						(arc
							(start -0.4064 -0.3937)
							(mid -0.478242 -0.363942)
							(end -0.508 -0.2921)
						)
						(arc
							(start -0.508 0.2921)
							(mid -0.478242 0.363942)
							(end -0.4064 0.3937)
						)
						(arc
							(start 0.4064 0.3937)
							(mid 0.478242 0.363942)
							(end 0.508 0.2921)
						)
					)
					(width 0)
					(fill yes)
				)
			)
		)
	)
	(footprint ""
		(layer "F.Cu")
		(at 181.102 -38.862 -90)
		(property "Reference" "R90"
			(at 0 0 270)
			(layer "F.SilkS")
			(hide yes)
			(effects
				(font
					(size 1.27 1.27)
				)
			)
		)
		(property "Value" "100R2F-L1-GP-U"
			(at 0.064008 -3.993896 270)
			(unlocked yes)
			(layer "F.Fab")
			(hide yes)
			(effects
				(font
					(size 1.016 1.016)
					(thickness 0.1524)
				)
			)
		)
		(property "Device Type" "R402H14"
			(at 0.064008 -5.517896 270)
			(unlocked yes)
			(layer "F.Fab")
			(hide yes)
			(effects
				(font
					(size 1.016 1.016)
					(thickness 0.1524)
				)
			)
		)
		(duplicate_pad_numbers_are_jumpers no)
		(fp_rect
			(start -0.381 0.8382)
			(end 0.381 -0.8382)
			(stroke
				(width 0)
				(type default)
			)
			(fill no)
			(layer "F.CrtYd")
		)
		(fp_rect
			(start -0.381 0.8382)
			(end 0.381 -0.8382)
			(stroke
				(width 0)
				(type default)
			)
			(fill no)
			(layer "F.Fab")
		)
		(pad "1" smd custom
			(at 0 -0.4318 270)
			(size 0.127 0.127)
			(layers "F.Cu" "F.Mask" "F.Paste")
			(net "SVID_CPU_DATA")
			(options
				(clearance outline)
				(anchor circle)
			)
			(primitives
				(gr_poly
					(pts
						(arc
							(start -0.2032 -0.2794)
							(mid -0.239121 -0.264521)
							(end -0.254 -0.2286)
						)
						(arc
							(start -0.254 0.2286)
							(mid -0.239121 0.264521)
							(end -0.2032 0.2794)
						)
						(arc
							(start 0.2032 0.2794)
							(mid 0.239121 0.264521)
							(end 0.254 0.2286)
						)
						(arc
							(start 0.254 -0.2286)
							(mid 0.239121 -0.264521)
							(end 0.2032 -0.2794)
						)
					)
					(width 0)
					(fill yes)
				)
			)
		)
		(pad "2" smd custom
			(at 0 0.4318 270)
			(size 0.127 0.127)
			(layers "F.Cu" "F.Mask" "F.Paste")
			(net "P1V0")
			(options
				(clearance outline)
				(anchor circle)
			)
			(primitives
				(gr_poly
					(pts
						(arc
							(start -0.2032 -0.2794)
							(mid -0.239121 -0.264521)
							(end -0.254 -0.2286)
						)
						(arc
							(start -0.254 0.2286)
							(mid -0.239121 0.264521)
							(end -0.2032 0.2794)
						)
						(arc
							(start 0.2032 0.2794)
							(mid 0.239121 0.264521)
							(end 0.254 0.2286)
						)
						(arc
							(start 0.254 -0.2286)
							(mid 0.239121 -0.264521)
							(end 0.2032 -0.2794)
						)
					)
					(width 0)
					(fill yes)
				)
			)
		)
	)
)
